(kicad_pcb
	(version 20260206)
	(generator "pcbnew")
	(generator_version "10.0")
	(general
		(thickness 1.6)
		(legacy_teardrops no)
	)
	(paper "A4")
	(title_block
		(title "Wiwynn_Tioga_Pass_MB.brd")
		(comment 1 "Tioga Pass / footprint 1664 of 4770 (U7C1), pads 115-229 of 1310")
	)
	(layers
		(0 "F.Cu" signal "TOP")
		(4 "In1.Cu" signal "L2GND")
		(6 "In2.Cu" signal "L3")
		(8 "In3.Cu" signal "L4GND")
		(10 "In4.Cu" signal "L5")
		(12 "In5.Cu" signal "L6GND")
		(14 "In6.Cu" signal "L7VCC")
		(16 "In7.Cu" signal "L8VCC")
		(18 "In8.Cu" signal "L9GND")
		(20 "In9.Cu" signal "L10")
		(22 "In10.Cu" signal "L11GND")
		(24 "In11.Cu" signal "L12")
		(26 "In12.Cu" signal "L13GND")
		(2 "B.Cu" signal "BOTTOM")
		(9 "F.Adhes" user "F.Adhesive")
		(11 "B.Adhes" user "B.Adhesive")
		(13 "F.Paste" user "Package Geometry/Pastemask Top")
		(15 "B.Paste" user "Package Geometry/Pastemask Bottom")
		(5 "F.SilkS" user "Ref Des/Silkscreen Top")
		(7 "B.SilkS" user "Ref Des/Silkscreen Bottom")
		(1 "F.Mask" user "Board Geometry/Soldermask Top")
		(3 "B.Mask" user "Board Geometry/Soldermask Bottom")
		(17 "Dwgs.User" user "User.Drawings")
		(19 "Cmts.User" user "User.Comments")
		(21 "Eco1.User" user "User.Eco1")
		(23 "Eco2.User" user "User.Eco2")
		(25 "Edge.Cuts" user "Board Geometry/Outline")
		(27 "Margin" user)
		(31 "F.CrtYd" user "Package Geometry/Place Bound Top")
		(29 "B.CrtYd" user "Package Geometry/Place Bound Bottom")
		(35 "F.Fab" user "Ref Des/Assembly Top")
		(33 "B.Fab" user "Ref Des/Assembly Bottom")
	)
	(footprint ""
		(layer "F.Cu")
		(at 387.985 -109.855 90)
		(property "Reference" "U7C1"
			(at 17.75333 -13.335 0)
			(unlocked yes)
			(layer "F.SilkS")
			(effects
				(font
					(size 0.7874 0.5842)
					(thickness 0.1524)
				)
				(justify left)
			)
		)
		(property "Value" ""
			(at 0 0 90)
			(layer "F.Fab")
			(effects
				(font
					(size 1.27 1.27)
				)
			)
		)
		(duplicate_pad_numbers_are_jumpers no)
		(pad "AE15" smd circle
			(at -10.30224 -2.72415)
			(size 0.381 0.381)
			(layers "F.Cu" "F.Mask" "F.Paste")
			(net "FM_PRSNT_2_2_N")
		)
		(pad "AE18" smd circle
			(at -8.5852 -2.72415)
			(size 0.381 0.381)
			(layers "F.Cu" "F.Mask" "F.Paste")
			(net "FM_PRSNT_2_1_N")
		)
		(pad "AE22" smd circle
			(at -6.86816 -2.72415)
			(size 0.381 0.381)
			(layers "F.Cu" "F.Mask" "F.Paste")
			(net "GND")
		)
		(pad "AE26" smd circle
			(at -5.20065 -2.64795 180)
			(size 0.381 0.381)
			(layers "F.Cu" "F.Mask" "F.Paste")
			(net "P1V8_PCH_STBY")
		)
		(pad "AE27" smd circle
			(at -4.40055 -2.64795 180)
			(size 0.381 0.381)
			(layers "F.Cu" "F.Mask" "F.Paste")
			(net "P1V05_PCH_STBY")
		)
		(pad "AE29" smd circle
			(at -3.60045 -2.64795 180)
			(size 0.381 0.381)
			(layers "F.Cu" "F.Mask" "F.Paste")
			(net "GND")
		)
		(pad "AE30" smd circle
			(at -2.80035 -2.64795 180)
			(size 0.381 0.381)
			(layers "F.Cu" "F.Mask" "F.Paste")
			(net "PVNN_PCH_STBY")
		)
		(pad "AE32" smd circle
			(at -2.00025 -2.64795 180)
			(size 0.381 0.381)
			(layers "F.Cu" "F.Mask" "F.Paste")
			(net "PVNN_PCH_STBY")
		)
		(pad "AE34" smd circle
			(at -1.20015 -2.64795 180)
			(size 0.381 0.381)
			(layers "F.Cu" "F.Mask" "F.Paste")
			(net "PVNN_PCH_STBY")
		)
		(pad "AE36" smd circle
			(at -0.40005 -2.64795 180)
			(size 0.381 0.381)
			(layers "F.Cu" "F.Mask" "F.Paste")
			(net "PVNN_PCH_STBY")
		)
		(pad "AE37" smd circle
			(at 0.40005 -2.64795 180)
			(size 0.381 0.381)
			(layers "F.Cu" "F.Mask" "F.Paste")
			(net "PVNN_PCH_STBY")
		)
		(pad "AE39" smd circle
			(at 1.20015 -2.64795 180)
			(size 0.381 0.381)
			(layers "F.Cu" "F.Mask" "F.Paste")
			(net "PVNN_PCH_STBY")
		)
		(pad "AE41" smd circle
			(at 2.00025 -2.64795 180)
			(size 0.381 0.381)
			(layers "F.Cu" "F.Mask" "F.Paste")
			(net "PVNN_PCH_STBY")
		)
		(pad "AE43" smd circle
			(at 2.80035 -2.64795 180)
			(size 0.381 0.381)
			(layers "F.Cu" "F.Mask" "F.Paste")
			(net "GND")
		)
		(pad "AE45" smd circle
			(at 3.60045 -2.64795 180)
			(size 0.381 0.381)
			(layers "F.Cu" "F.Mask" "F.Paste")
			(net "P1V05_PCH_STBY_VCCA_PLL1")
		)
		(pad "AE46" smd circle
			(at 4.40055 -2.64795 180)
			(size 0.381 0.381)
			(layers "F.Cu" "F.Mask" "F.Paste")
			(net "P1V05_PCH_STBY_ISCLK_PLL")
		)
		(pad "AE48" smd circle
			(at 5.20065 -2.64795 180)
			(size 0.381 0.381)
			(layers "F.Cu" "F.Mask" "F.Paste")
			(net "GND")
		)
		(pad "AE52" smd circle
			(at 6.86816 -2.72415)
			(size 0.381 0.381)
			(layers "F.Cu" "F.Mask" "F.Paste")
			(net "GND")
		)
		(pad "AE56" smd circle
			(at 8.5852 -2.72415)
			(size 0.381 0.381)
			(layers "F.Cu" "F.Mask" "F.Paste")
			(net "GND")
		)
		(pad "AE59" smd circle
			(at 10.30224 -2.72415)
			(size 0.381 0.381)
			(layers "F.Cu" "F.Mask" "F.Paste")
			(net "GND")
		)
		(pad "AE63" smd circle
			(at 12.01928 -2.72415)
			(size 0.381 0.381)
			(layers "F.Cu" "F.Mask" "F.Paste")
			(net "GND")
		)
		(pad "AE66" smd circle
			(at 13.73632 -2.72415)
			(size 0.381 0.381)
			(layers "F.Cu" "F.Mask" "F.Paste")
			(net "GND")
		)
		(pad "AE69" smd circle
			(at 15.064994 -2.500122)
			(size 0.3048 0.3048)
			(layers "F.Cu" "F.Mask" "F.Paste")
			(net "Net_143")
		)
		(pad "AE71" smd circle
			(at 15.895066 -2.500122)
			(size 0.3048 0.3048)
			(layers "F.Cu" "F.Mask" "F.Paste")
			(net "Net_147")
		)
		(pad "AF1" smd oval
			(at -16.310102 -1.999996 180)
			(size 0.254 0.3302)
			(layers "F.Cu" "F.Mask" "F.Paste")
			(net "GND")
		)
		(pad "AF3" smd circle
			(at -15.48003 -1.999996 180)
			(size 0.3048 0.3048)
			(layers "F.Cu" "F.Mask" "F.Paste")
			(net "GND")
		)
		(pad "AF5" smd circle
			(at -14.649958 -1.999996 180)
			(size 0.3048 0.3048)
			(layers "F.Cu" "F.Mask" "F.Paste")
			(net "GND")
		)
		(pad "AF9" smd circle
			(at -12.8778 -2.22885)
			(size 0.381 0.381)
			(layers "F.Cu" "F.Mask" "F.Paste")
			(net "GND")
		)
		(pad "AF13" smd circle
			(at -11.16076 -2.22885)
			(size 0.381 0.381)
			(layers "F.Cu" "F.Mask" "F.Paste")
			(net "GND")
		)
		(pad "AF17" smd circle
			(at -9.44372 -2.22885)
			(size 0.381 0.381)
			(layers "F.Cu" "F.Mask" "F.Paste")
			(net "GND")
		)
		(pad "AF20" smd circle
			(at -7.72668 -2.22885)
			(size 0.381 0.381)
			(layers "F.Cu" "F.Mask" "F.Paste")
			(net "TP_PCH_GPP_L10")
		)
		(pad "AF24" smd circle
			(at -6.00964 -2.22885)
			(size 0.381 0.381)
			(layers "F.Cu" "F.Mask" "F.Paste")
			(net "GND")
		)
		(pad "AF50" smd circle
			(at 6.00964 -2.22885)
			(size 0.381 0.381)
			(layers "F.Cu" "F.Mask" "F.Paste")
			(net "GND")
		)
		(pad "AF54" smd circle
			(at 7.72668 -2.22885)
			(size 0.381 0.381)
			(layers "F.Cu" "F.Mask" "F.Paste")
			(net "XDP_PCH_CPU_TCK0")
		)
		(pad "AF58" smd circle
			(at 9.44372 -2.22885)
			(size 0.381 0.381)
			(layers "F.Cu" "F.Mask" "F.Paste")
			(net "A_PCIEUP_RCOMP_N")
		)
		(pad "AF61" smd circle
			(at 11.16076 -2.22885)
			(size 0.381 0.381)
			(layers "F.Cu" "F.Mask" "F.Paste")
			(net "TP_PCH_RSVD0")
		)
		(pad "AF65" smd circle
			(at 12.8778 -2.22885)
			(size 0.381 0.381)
			(layers "F.Cu" "F.Mask" "F.Paste")
			(net "SATA6G_PCH_PCIE_UP_SATA_RXN<4>")
		)
		(pad "AF68" smd circle
			(at 14.649958 -1.999996)
			(size 0.3048 0.3048)
			(layers "F.Cu" "F.Mask" "F.Paste")
			(net "GND")
		)
		(pad "AF70" smd circle
			(at 15.48003 -1.999996)
			(size 0.3048 0.3048)
			(layers "F.Cu" "F.Mask" "F.Paste")
			(net "Net_142")
		)
		(pad "AF72" smd oval
			(at 16.310102 -1.999996 180)
			(size 0.254 0.3302)
			(layers "F.Cu" "F.Mask" "F.Paste")
			(net "Net_146")
		)
		(pad "AG7" smd circle
			(at -13.73632 -1.73355)
			(size 0.381 0.381)
			(layers "F.Cu" "F.Mask" "F.Paste")
			(net "IRQ_OC_DETECT_N")
		)
		(pad "AG11" smd circle
			(at -12.01928 -1.73355)
			(size 0.381 0.381)
			(layers "F.Cu" "F.Mask" "F.Paste")
			(net "FM_CPU_ERR1_PCH_N")
		)
		(pad "AG15" smd circle
			(at -10.30224 -1.73355)
			(size 0.381 0.381)
			(layers "F.Cu" "F.Mask" "F.Paste")
			(net "TP_PCH_RSVD5")
		)
		(pad "AG18" smd circle
			(at -8.5852 -1.73355)
			(size 0.381 0.381)
			(layers "F.Cu" "F.Mask" "F.Paste")
			(net "FM_INTRUDER_HDR_PCH_N")
		)
		(pad "AG22" smd circle
			(at -6.86816 -1.73355)
			(size 0.381 0.381)
			(layers "F.Cu" "F.Mask" "F.Paste")
			(net "A_PVCCRTC_EXT_CAP")
		)
		(pad "AG26" smd circle
			(at -5.20065 -1.84785 180)
			(size 0.381 0.381)
			(layers "F.Cu" "F.Mask" "F.Paste")
			(net "GND")
		)
		(pad "AG27" smd circle
			(at -4.40055 -1.84785 180)
			(size 0.381 0.381)
			(layers "F.Cu" "F.Mask" "F.Paste")
			(net "P1V8_PCH_STBY")
		)
		(pad "AG29" smd circle
			(at -3.60045 -1.84785 180)
			(size 0.381 0.381)
			(layers "F.Cu" "F.Mask" "F.Paste")
			(net "P3V3_STBY")
		)
		(pad "AG30" smd circle
			(at -2.80035 -1.84785 180)
			(size 0.381 0.381)
			(layers "F.Cu" "F.Mask" "F.Paste")
			(net "GND")
		)
		(pad "AG32" smd circle
			(at -2.00025 -1.84785 180)
			(size 0.381 0.381)
			(layers "F.Cu" "F.Mask" "F.Paste")
			(net "PVNN_PCH_STBY")
		)
		(pad "AG34" smd circle
			(at -1.20015 -1.84785 180)
			(size 0.381 0.381)
			(layers "F.Cu" "F.Mask" "F.Paste")
			(net "PVNN_PCH_STBY")
		)
		(pad "AG36" smd circle
			(at -0.40005 -1.84785 180)
			(size 0.381 0.381)
			(layers "F.Cu" "F.Mask" "F.Paste")
			(net "PVNN_PCH_STBY")
		)
		(pad "AG37" smd circle
			(at 0.40005 -1.84785 180)
			(size 0.381 0.381)
			(layers "F.Cu" "F.Mask" "F.Paste")
			(net "PVNN_PCH_STBY")
		)
		(pad "AG39" smd circle
			(at 1.20015 -1.84785 180)
			(size 0.381 0.381)
			(layers "F.Cu" "F.Mask" "F.Paste")
			(net "PVNN_PCH_STBY")
		)
		(pad "AG41" smd circle
			(at 2.00025 -1.84785 180)
			(size 0.381 0.381)
			(layers "F.Cu" "F.Mask" "F.Paste")
			(net "GND")
		)
		(pad "AG43" smd circle
			(at 2.80035 -1.84785 180)
			(size 0.381 0.381)
			(layers "F.Cu" "F.Mask" "F.Paste")
			(net "GND")
		)
		(pad "AG45" smd circle
			(at 3.60045 -1.84785 180)
			(size 0.381 0.381)
			(layers "F.Cu" "F.Mask" "F.Paste")
			(net "P1V05_PCH_STBY_ISCLK_PLL")
		)
		(pad "AG46" smd circle
			(at 4.40055 -1.84785 180)
			(size 0.381 0.381)
			(layers "F.Cu" "F.Mask" "F.Paste")
			(net "GND")
		)
		(pad "AG48" smd circle
			(at 5.20065 -1.84785 180)
			(size 0.381 0.381)
			(layers "F.Cu" "F.Mask" "F.Paste")
			(net "P1V05_PCH_STBY_VCCA_PLL0")
		)
		(pad "AG52" smd circle
			(at 6.86816 -1.73355)
			(size 0.381 0.381)
			(layers "F.Cu" "F.Mask" "F.Paste")
			(net "GND")
		)
		(pad "AG56" smd circle
			(at 8.5852 -1.73355)
			(size 0.381 0.381)
			(layers "F.Cu" "F.Mask" "F.Paste")
			(net "GND")
		)
		(pad "AG59" smd circle
			(at 10.30224 -1.73355)
			(size 0.381 0.381)
			(layers "F.Cu" "F.Mask" "F.Paste")
			(net "GND")
		)
		(pad "AG63" smd circle
			(at 12.01928 -1.73355)
			(size 0.381 0.381)
			(layers "F.Cu" "F.Mask" "F.Paste")
			(net "SATA6G_PCH_PCIE_UP_SATA_RXP<5>")
		)
		(pad "AG66" smd circle
			(at 13.73632 -1.73355)
			(size 0.381 0.381)
			(layers "F.Cu" "F.Mask" "F.Paste")
			(net "GND")
		)
		(pad "AH2" smd circle
			(at -15.895066 -1.500124 180)
			(size 0.3048 0.3048)
			(layers "F.Cu" "F.Mask" "F.Paste")
			(net "RMII_BMC_PCH_SPRNGVLLE_RXER_R")
		)
		(pad "AH4" smd circle
			(at -15.064994 -1.500124 180)
			(size 0.3048 0.3048)
			(layers "F.Cu" "F.Mask" "F.Paste")
			(net "RST_PCIE_PCH_PERST_N")
		)
		(pad "AH9" smd circle
			(at -12.8778 -1.23825)
			(size 0.381 0.381)
			(layers "F.Cu" "F.Mask" "F.Paste")
			(net "JTAG_PCH_PLD_TMS")
		)
		(pad "AH13" smd circle
			(at -11.16076 -1.23825)
			(size 0.381 0.381)
			(layers "F.Cu" "F.Mask" "F.Paste")
			(net "FM_BMC_READY_R1_N")
		)
		(pad "AH17" smd circle
			(at -9.44372 -1.23825)
			(size 0.381 0.381)
			(layers "F.Cu" "F.Mask" "F.Paste")
			(net "FM_BIOS_USB_RECOVERY")
		)
		(pad "AH20" smd circle
			(at -7.72668 -1.23825)
			(size 0.381 0.381)
			(layers "F.Cu" "F.Mask" "F.Paste")
			(net "GND")
		)
		(pad "AH24" smd circle
			(at -6.00964 -1.23825)
			(size 0.381 0.381)
			(layers "F.Cu" "F.Mask" "F.Paste")
			(net "P3V3_STBY")
		)
		(pad "AH50" smd circle
			(at 6.00964 -1.23825)
			(size 0.381 0.381)
			(layers "F.Cu" "F.Mask" "F.Paste")
			(net "P1V05_PCH_STBY")
		)
		(pad "AH54" smd circle
			(at 7.72668 -1.23825)
			(size 0.381 0.381)
			(layers "F.Cu" "F.Mask" "F.Paste")
			(net "XDP_TMS")
		)
		(pad "AH58" smd circle
			(at 9.44372 -1.23825)
			(size 0.381 0.381)
			(layers "F.Cu" "F.Mask" "F.Paste")
			(net "A_PCIEUP_RCOMP_P")
		)
		(pad "AH61" smd circle
			(at 11.16076 -1.23825)
			(size 0.381 0.381)
			(layers "F.Cu" "F.Mask" "F.Paste")
			(net "SATA6G_PCH_PCIE_UP_SATA_RXN<5>")
		)
		(pad "AH65" smd circle
			(at 12.8778 -1.23825)
			(size 0.381 0.381)
			(layers "F.Cu" "F.Mask" "F.Paste")
			(net "SATA6G_PCH_PCIE_UP_SATA_RXP<4>")
		)
		(pad "AH69" smd circle
			(at 15.064994 -1.500124)
			(size 0.3048 0.3048)
			(layers "F.Cu" "F.Mask" "F.Paste")
			(net "SATA6G_S1_TX_DN")
		)
		(pad "AH71" smd circle
			(at 15.895066 -1.500124)
			(size 0.3048 0.3048)
			(layers "F.Cu" "F.Mask" "F.Paste")
			(net "SATA6G_S1_TX_DP")
		)
		(pad "AJ1" smd oval
			(at -16.310102 -0.999998 180)
			(size 0.254 0.3302)
			(layers "F.Cu" "F.Mask" "F.Paste")
			(net "CLK_50M_CKMNG_PCH_10GBE")
		)
		(pad "AJ3" smd circle
			(at -15.48003 -0.999998 180)
			(size 0.3048 0.3048)
			(layers "F.Cu" "F.Mask" "F.Paste")
			(net "RMII_PCH_SPRNGVLLE_ARB_IN")
		)
		(pad "AJ5" smd circle
			(at -14.649958 -0.999998 180)
			(size 0.3048 0.3048)
			(layers "F.Cu" "F.Mask" "F.Paste")
			(net "GND")
		)
		(pad "AJ7" smd circle
			(at -13.73632 -0.74295)
			(size 0.381 0.381)
			(layers "F.Cu" "F.Mask" "F.Paste")
			(net "GND")
		)
		(pad "AJ11" smd circle
			(at -12.01928 -0.74295)
			(size 0.381 0.381)
			(layers "F.Cu" "F.Mask" "F.Paste")
			(net "GND")
		)
		(pad "AJ15" smd circle
			(at -10.30224 -0.74295)
			(size 0.381 0.381)
			(layers "F.Cu" "F.Mask" "F.Paste")
			(net "GND")
		)
		(pad "AJ18" smd circle
			(at -8.5852 -0.74295)
			(size 0.381 0.381)
			(layers "F.Cu" "F.Mask" "F.Paste")
			(net "GND")
		)
		(pad "AJ22" smd circle
			(at -6.86816 -0.74295)
			(size 0.381 0.381)
			(layers "F.Cu" "F.Mask" "F.Paste")
			(net "GND")
		)
		(pad "AJ26" smd circle
			(at -5.20065 -1.04775 180)
			(size 0.381 0.381)
			(layers "F.Cu" "F.Mask" "F.Paste")
			(net "GND")
		)
		(pad "AJ27" smd circle
			(at -4.40055 -1.04775 180)
			(size 0.381 0.381)
			(layers "F.Cu" "F.Mask" "F.Paste")
			(net "P3V3_RTC_STBY")
		)
		(pad "AJ29" smd circle
			(at -3.60045 -1.04775 180)
			(size 0.381 0.381)
			(layers "F.Cu" "F.Mask" "F.Paste")
			(net "P1V05_PCH_STBY")
		)
		(pad "AJ30" smd circle
			(at -2.80035 -1.04775 180)
			(size 0.381 0.381)
			(layers "F.Cu" "F.Mask" "F.Paste")
			(net "GND")
		)
		(pad "AJ32" smd circle
			(at -2.00025 -1.04775 180)
			(size 0.381 0.381)
			(layers "F.Cu" "F.Mask" "F.Paste")
			(net "GND")
		)
		(pad "AJ34" smd circle
			(at -1.20015 -1.04775 180)
			(size 0.381 0.381)
			(layers "F.Cu" "F.Mask" "F.Paste")
			(net "GND")
		)
		(pad "AJ36" smd circle
			(at -0.40005 -1.04775 180)
			(size 0.381 0.381)
			(layers "F.Cu" "F.Mask" "F.Paste")
			(net "GND")
		)
		(pad "AJ37" smd circle
			(at 0.40005 -1.04775 180)
			(size 0.381 0.381)
			(layers "F.Cu" "F.Mask" "F.Paste")
			(net "GND")
		)
		(pad "AJ39" smd circle
			(at 1.20015 -1.04775 180)
			(size 0.381 0.381)
			(layers "F.Cu" "F.Mask" "F.Paste")
			(net "GND")
		)
		(pad "AJ41" smd circle
			(at 2.00025 -1.04775 180)
			(size 0.381 0.381)
			(layers "F.Cu" "F.Mask" "F.Paste")
			(net "GND")
		)
		(pad "AJ43" smd circle
			(at 2.80035 -1.04775 180)
			(size 0.381 0.381)
			(layers "F.Cu" "F.Mask" "F.Paste")
			(net "P1V05_PCH_STBY")
		)
		(pad "AJ45" smd circle
			(at 3.60045 -1.04775 180)
			(size 0.381 0.381)
			(layers "F.Cu" "F.Mask" "F.Paste")
			(net "GND")
		)
		(pad "AJ46" smd circle
			(at 4.40055 -1.04775 180)
			(size 0.381 0.381)
			(layers "F.Cu" "F.Mask" "F.Paste")
			(net "P1V05_PCH_STBY_ISCLK_PLL")
		)
		(pad "AJ48" smd circle
			(at 5.20065 -1.04775 180)
			(size 0.381 0.381)
			(layers "F.Cu" "F.Mask" "F.Paste")
			(net "P1V05_PCH_STBY_ISCLK_PLL")
		)
		(pad "AJ52" smd circle
			(at 6.86816 -0.74295)
			(size 0.381 0.381)
			(layers "F.Cu" "F.Mask" "F.Paste")
			(net "GND")
		)
		(pad "AJ56" smd circle
			(at 8.5852 -0.74295)
			(size 0.381 0.381)
			(layers "F.Cu" "F.Mask" "F.Paste")
			(net "GND")
		)
		(pad "AJ59" smd circle
			(at 10.30224 -0.74295)
			(size 0.381 0.381)
			(layers "F.Cu" "F.Mask" "F.Paste")
			(net "GND")
		)
		(pad "AJ63" smd circle
			(at 12.01928 -0.74295)
			(size 0.381 0.381)
			(layers "F.Cu" "F.Mask" "F.Paste")
			(net "SATA6G_PCH_PCIE_UP_SATA_RXP<2>")
		)
		(pad "AJ66" smd circle
			(at 13.73632 -0.74295)
			(size 0.381 0.381)
			(layers "F.Cu" "F.Mask" "F.Paste")
			(net "GND")
		)
		(pad "AJ68" smd circle
			(at 14.649958 -0.999998)
			(size 0.3048 0.3048)
			(layers "F.Cu" "F.Mask" "F.Paste")
			(net "GND")
		)
		(pad "AJ70" smd circle
			(at 15.48003 -0.999998)
			(size 0.3048 0.3048)
			(layers "F.Cu" "F.Mask" "F.Paste")
			(net "SATA6G_S0_TX_DN")
		)
		(pad "AJ72" smd oval
			(at 16.310102 -0.999998 180)
			(size 0.254 0.3302)
			(layers "F.Cu" "F.Mask" "F.Paste")
			(net "SATA6G_S0_TX_DP")
		)
		(pad "AK2" smd circle
			(at -15.895066 -0.500126 180)
			(size 0.3048 0.3048)
			(layers "F.Cu" "F.Mask" "F.Paste")
			(net "RMII_BMC_PCH_SPRNGVLLE_TXD1")
		)
		(pad "AK4" smd circle
			(at -15.064994 -0.500126 180)
			(size 0.3048 0.3048)
			(layers "F.Cu" "F.Mask" "F.Paste")
			(net "RMII_PCH_SPRNGVLLE_ARB_OUT_R")
		)
		(pad "AK9" smd circle
			(at -12.8778 -0.24765)
			(size 0.381 0.381)
			(layers "F.Cu" "F.Mask" "F.Paste")
			(net "FM_HSC_TIMER_EXP_N")
		)
		(pad "AK13" smd circle
			(at -11.16076 -0.24765)
			(size 0.381 0.381)
			(layers "F.Cu" "F.Mask" "F.Paste")
			(net "FM_MP_PS_REDUNDANT_LOST_N")
		)
		(pad "AK17" smd circle
			(at -9.44372 -0.24765)
			(size 0.381 0.381)
			(layers "F.Cu" "F.Mask" "F.Paste")
			(net "JTAG_PCH_PLD_TDI")
		)
		(pad "AK20" smd circle
			(at -7.72668 -0.24765)
			(size 0.381 0.381)
			(layers "F.Cu" "F.Mask" "F.Paste")
			(net "FM_MP_PS_FAIL_N")
		)
		(pad "AK24" smd circle
			(at -6.00964 -0.24765)
			(size 0.381 0.381)
			(layers "F.Cu" "F.Mask" "F.Paste")
			(net "P1V8_PCH_STBY")
		)
	)
)
